# BASEBOARD_FAB2 (Tioga Pass) — schematic netlist excerpt (pin names and nets, part order shuffled) for the footprints in the layout excerpt that follows; sources: Cadence DE-HDL packaged netlist, KiCad conversion of Wiwynn_Tioga_Pass_MB.brd

CONX8  SMC-CONN60A-22-GP  pkg CONN-G7  page 245
  \1\  = GND
  \2\  = NC
  \3\  = P3E_CPU0_PE2_SS_C_TXN<8>
  \4\  = GND
  \5\  = P3E_CPU0_PE2_SS_C_TXP<8>
  \6\  = P3E_CPU0_PE2_SS_RXN<8>
  \7\  = GND
  \8\  = P3E_CPU0_PE2_SS_RXP<8>
  \9\  = P3E_CPU0_PE2_SS_C_TXN<9>
  \10\  = GND
  \11\  = P3E_CPU0_PE2_SS_C_TXP<9>
  \12\  = P3E_CPU0_PE2_SS_RXN<9>
  \13\  = GND
  \14\  = P3E_CPU0_PE2_SS_RXP<9>
  \15\  = P3E_CPU0_PE2_SS_C_TXN<10>
  \16\  = GND
  \17\  = P3E_CPU0_PE2_SS_C_TXP<10>
  \18\  = P3E_CPU0_PE2_SS_RXN<10>
  \19\  = GND
  \20\  = P3E_CPU0_PE2_SS_RXP<10>
  \21\  = P3E_CPU0_PE2_SS_C_TXP<11>
  \22\  = GND
  \23\  = P3E_CPU0_PE2_SS_C_TXN<11>
  \24\  = P3E_CPU0_PE2_SS_RXN<11>
  \25\  = GND
  \26\  = P3E_CPU0_PE2_SS_RXP<11>
  \27\  = P3E_CPU0_PE2_SS_C_TXN<12>
  \28\  = GND
  \29\  = P3E_CPU0_PE2_SS_C_TXP<12>
  \30\  = P3E_CPU0_PE2_SS_RXN<12>
  \31\  = GND
  \32\  = P3E_CPU0_PE2_SS_RXP<12>
  \33\  = P3E_CPU0_PE2_SS_C_TXN<13>
  \34\  = GND
  \35\  = P3E_CPU0_PE2_SS_C_TXP<13>
  \36\  = P3E_CPU0_PE2_SS_RXP<13>
  \37\  = GND
  \38\  = P3E_CPU0_PE2_SS_RXN<13>
  \39\  = P3E_CPU0_PE2_SS_C_TXP<14>
  \40\  = GND
  \41\  = P3E_CPU0_PE2_SS_C_TXN<14>
  \42\  = P3E_CPU0_PE2_SS_RXN<14>
  \43\  = GND
  \44\  = P3E_CPU0_PE2_SS_RXP<14>
  \45\  = P3E_CPU0_PE2_SS_C_TXN<15>
  \46\  = GND
  \47\  = P3E_CPU0_PE2_SS_C_TXP<15>
  \48\  = P3E_CPU0_PE2_SS_RXN<15>
  \49\  = GND
  \50\  = P3E_CPU0_PE2_SS_RXP<15>
  \51\  = JTAG_RISER_TDI
  \52\  = GND
  \53\  = JTAG_RISER_TDO
  \54\  = JTAG_RISER_TMS
  \55\  = GND
  \56\  = JTAG_RISER_TCK
  \57\  = USB2_P02_DN
  \58\  = GND
  \59\  = USB2_P02_DP
  \60\  = JTAG_RISER_TRST
  NP1  = NC
  NP2  = NC
  PTH1  = GND
  PTH2  = GND

(kicad_pcb
	(version 20260206)
	(generator "pcbnew")
	(generator_version "10.0")
	(general
		(thickness 1.6)
		(legacy_teardrops no)
	)
	(paper "A4")
	(title_block
		(title "Wiwynn_Tioga_Pass_MB.brd")
		(comment 1 "Tioga Pass / footprint 865 of 4770 (CONX8), pads 44-64 of 64")
	)
	(layers
		(0 "F.Cu" signal "TOP")
		(4 "In1.Cu" signal "L2GND")
		(6 "In2.Cu" signal "L3")
		(8 "In3.Cu" signal "L4GND")
		(10 "In4.Cu" signal "L5")
		(12 "In5.Cu" signal "L6GND")
		(14 "In6.Cu" signal "L7VCC")
		(16 "In7.Cu" signal "L8VCC")
		(18 "In8.Cu" signal "L9GND")
		(20 "In9.Cu" signal "L10")
		(22 "In10.Cu" signal "L11GND")
		(24 "In11.Cu" signal "L12")
		(26 "In12.Cu" signal "L13GND")
		(2 "B.Cu" signal "BOTTOM")
		(9 "F.Adhes" user "F.Adhesive")
		(11 "B.Adhes" user "B.Adhesive")
		(13 "F.Paste" user "Package Geometry/Pastemask Top")
		(15 "B.Paste" user "Package Geometry/Pastemask Bottom")
		(5 "F.SilkS" user "Ref Des/Silkscreen Top")
		(7 "B.SilkS" user "Ref Des/Silkscreen Bottom")
		(1 "F.Mask" user "Board Geometry/Soldermask Top")
		(3 "B.Mask" user "Board Geometry/Soldermask Bottom")
		(17 "Dwgs.User" user "User.Drawings")
		(19 "Cmts.User" user "User.Comments")
		(21 "Eco1.User" user "User.Eco1")
		(23 "Eco2.User" user "User.Eco2")
		(25 "Edge.Cuts" user "Board Geometry/Outline")
		(27 "Margin" user)
		(31 "F.CrtYd" user "Package Geometry/Place Bound Top")
		(29 "B.CrtYd" user "Package Geometry/Place Bound Bottom")
		(35 "F.Fab" user "Ref Des/Assembly Top")
		(33 "B.Fab" user "Ref Des/Assembly Bottom")
	)
	(footprint ""
		(layer "F.Cu")
		(at 369.085114 -6.089904 180)
		(property "Reference" "CONX8"
			(at 0 0 180)
			(layer "F.SilkS")
			(hide yes)
			(effects
				(font
					(size 1.27 1.27)
				)
			)
		)
		(property "Value" "*"
			(at -14.3129 -7.5565 180)
			(unlocked yes)
			(layer "F.Fab")
			(hide yes)
			(effects
				(font
					(size 1.27 1.016)
					(thickness 0.1524)
				)
			)
		)
		(property "Device Type" "SMC-CONN60A-22-GP_CONN-G7-SMC-A"
			(at -14.3129 -9.0805 180)
			(unlocked yes)
			(layer "F.Fab")
			(hide yes)
			(effects
				(font
					(size 1.27 1.016)
					(thickness 0.1524)
				)
			)
		)
		(duplicate_pad_numbers_are_jumpers no)
		(pad "42" smd rect
			(at 4.400042 -1.700022 180)
			(size 0.508 1.1938)
			(layers "F.Cu" "F.Mask" "F.Paste")
			(net "P3E_CPU0_PE2_SS_RXN<14>")
		)
		(pad "43" smd rect
			(at 5.199888 1.700022 180)
			(size 0.508 1.1938)
			(layers "F.Cu" "F.Mask" "F.Paste")
			(net "GND")
		)
		(pad "44" smd rect
			(at 5.199888 -1.700022 180)
			(size 0.508 1.1938)
			(layers "F.Cu" "F.Mask" "F.Paste")
			(net "P3E_CPU0_PE2_SS_RXP<14>")
		)
		(pad "45" smd rect
			(at 5.999988 1.700022 180)
			(size 0.508 1.1938)
			(layers "F.Cu" "F.Mask" "F.Paste")
			(net "P3E_CPU0_PE2_SS_C_TXN<15>")
		)
		(pad "46" smd rect
			(at 5.999988 -1.700022 180)
			(size 0.508 1.1938)
			(layers "F.Cu" "F.Mask" "F.Paste")
			(net "GND")
		)
		(pad "47" smd rect
			(at 6.800088 1.700022 180)
			(size 0.508 1.1938)
			(layers "F.Cu" "F.Mask" "F.Paste")
			(net "P3E_CPU0_PE2_SS_C_TXP<15>")
		)
		(pad "48" smd rect
			(at 6.800088 -1.700022 180)
			(size 0.508 1.1938)
			(layers "F.Cu" "F.Mask" "F.Paste")
			(net "P3E_CPU0_PE2_SS_RXN<15>")
		)
		(pad "49" smd rect
			(at 7.599934 1.700022 180)
			(size 0.508 1.1938)
			(layers "F.Cu" "F.Mask" "F.Paste")
			(net "GND")
		)
		(pad "50" smd rect
			(at 7.599934 -1.700022 180)
			(size 0.508 1.1938)
			(layers "F.Cu" "F.Mask" "F.Paste")
			(net "P3E_CPU0_PE2_SS_RXP<15>")
		)
		(pad "51" smd rect
			(at 8.400034 1.700022 180)
			(size 0.508 1.1938)
			(layers "F.Cu" "F.Mask" "F.Paste")
			(net "JTAG_RISER_TDI")
		)
		(pad "52" smd rect
			(at 8.400034 -1.700022 180)
			(size 0.508 1.1938)
			(layers "F.Cu" "F.Mask" "F.Paste")
			(net "GND")
		)
		(pad "53" smd rect
			(at 9.19988 1.700022 180)
			(size 0.508 1.1938)
			(layers "F.Cu" "F.Mask" "F.Paste")
			(net "JTAG_RISER_TDO")
		)
		(pad "54" smd rect
			(at 9.19988 -1.700022 180)
			(size 0.508 1.1938)
			(layers "F.Cu" "F.Mask" "F.Paste")
			(net "JTAG_RISER_TMS")
		)
		(pad "55" smd rect
			(at 9.99998 1.700022 180)
			(size 0.508 1.1938)
			(layers "F.Cu" "F.Mask" "F.Paste")
			(net "GND")
		)
		(pad "56" smd rect
			(at 9.99998 -1.700022 180)
			(size 0.508 1.1938)
			(layers "F.Cu" "F.Mask" "F.Paste")
			(net "JTAG_RISER_TCK")
		)
		(pad "57" smd rect
			(at 10.80008 1.700022 180)
			(size 0.508 1.1938)
			(layers "F.Cu" "F.Mask" "F.Paste")
			(net "USB2_P02_DN")
		)
		(pad "58" smd rect
			(at 10.80008 -1.700022 180)
			(size 0.508 1.1938)
			(layers "F.Cu" "F.Mask" "F.Paste")
			(net "GND")
		)
		(pad "59" smd rect
			(at 11.599926 1.700022 180)
			(size 0.508 1.1938)
			(layers "F.Cu" "F.Mask" "F.Paste")
			(net "USB2_P02_DP")
		)
		(pad "60" smd rect
			(at 11.599926 -1.700022 180)
			(size 0.508 1.1938)
			(layers "F.Cu" "F.Mask" "F.Paste")
			(net "JTAG_RISER_TRST")
		)
		(pad "PTH1" thru_hole circle
			(at -15.450058 0 180)
			(size 1.27 1.27)
			(drill 0.8636)
			(layers "*.Cu" "*.Mask")
			(remove_unused_layers no)
			(net "GND")
			(clearance 0.1524)
			(thermal_gap 0.1524)
		)
		(pad "PTH2" thru_hole circle
			(at 15.450058 0 180)
			(size 1.27 1.27)
			(drill 0.8636)
			(layers "*.Cu" "*.Mask")
			(remove_unused_layers no)
			(net "GND")
			(clearance 0.1524)
			(thermal_gap 0.1524)
		)
	)
)
